(kicad_pcb
	(version 20260206)
	(generator "pcbnew")
	(generator_version "10.0")
	(general
		(thickness 1.6)
		(legacy_teardrops no)
	)
	(paper "A4")
	(title_block
		(title "03242023_DA0F0TMBIJ0_F0T_Motherboard_J_brd_V01_OCP.brd")
		(comment 1 "Grand Teton / footprints 4172-4177 of 6105")
	)
	(layers
		(0 "F.Cu" signal "TOP")
		(4 "In1.Cu" signal "GND")
		(6 "In2.Cu" signal "IN1")
		(8 "In3.Cu" signal "GND1")
		(10 "In4.Cu" signal "IN2")
		(12 "In5.Cu" signal "GND2")
		(14 "In6.Cu" signal "IN3")
		(16 "In7.Cu" signal "GND3")
		(18 "In8.Cu" signal "VCC")
		(20 "In9.Cu" signal "VCC1")
		(22 "In10.Cu" signal "GND4")
		(24 "In11.Cu" signal "IN4")
		(26 "In12.Cu" signal "GND5")
		(28 "In13.Cu" signal "IN5")
		(30 "In14.Cu" signal "GND6")
		(32 "In15.Cu" signal "IN6")
		(34 "In16.Cu" signal "GND7")
		(2 "B.Cu" signal "BOTTOM")
		(9 "F.Adhes" user "F.Adhesive")
		(11 "B.Adhes" user "B.Adhesive")
		(13 "F.Paste" user "Package Geometry/Pastemask Top")
		(15 "B.Paste" user "Package Geometry/Pastemask Bottom")
		(5 "F.SilkS" user "Ref Des/Silkscreen Top")
		(7 "B.SilkS" user "Ref Des/Silkscreen Bottom")
		(1 "F.Mask" user "Board Geometry/Soldermask Top")
		(3 "B.Mask" user "Board Geometry/Soldermask Bottom")
		(17 "Dwgs.User" user "User.Drawings")
		(19 "Cmts.User" user "User.Comments")
		(21 "Eco1.User" user "User.Eco1")
		(23 "Eco2.User" user "User.Eco2")
		(25 "Edge.Cuts" user "Board Geometry/Outline")
		(27 "Margin" user)
		(31 "F.CrtYd" user "Package Geometry/Place Bound Top")
		(29 "B.CrtYd" user "Package Geometry/Place Bound Bottom")
		(35 "F.Fab" user "Ref Des/Assembly Top")
		(33 "B.Fab" user "Ref Des/Assembly Bottom")
	)
	(footprint ""
		(layer "B.Cu")
		(at 423.650156 -318.781176)
		(property "Reference" "R37"
			(at 0 0 0)
			(layer "B.SilkS")
			(hide yes)
			(effects
				(font
					(size 1.27 1.27)
				)
				(justify mirror)
			)
		)
		(property "Value" ""
			(at 0 0 0)
			(layer "B.Fab")
			(effects
				(font
					(size 1.27 1.27)
				)
				(justify mirror)
			)
		)
		(duplicate_pad_numbers_are_jumpers no)
		(fp_line
			(start -0.7874 -0.4064)
			(end -0.7874 0.4064)
			(stroke
				(width 0.1524)
				(type default)
			)
			(layer "B.SilkS")
		)
		(fp_line
			(start -0.7874 0.4064)
			(end 0.7874 0.4064)
			(stroke
				(width 0.1524)
				(type default)
			)
			(layer "B.SilkS")
		)
		(fp_line
			(start 0.7874 -0.4064)
			(end -0.7874 -0.4064)
			(stroke
				(width 0.1524)
				(type default)
			)
			(layer "B.SilkS")
		)
		(fp_line
			(start 0.7874 0.4064)
			(end 0.7874 -0.4064)
			(stroke
				(width 0.1524)
				(type default)
			)
			(layer "B.SilkS")
		)
		(fp_line
			(start -0.67945 -0.3048)
			(end -0.67945 0.3048)
			(stroke
				(width 0.1)
				(type default)
			)
			(layer "B.Fab")
		)
		(fp_line
			(start -0.67945 0.3048)
			(end -0.120396 0.3048)
			(stroke
				(width 0.1)
				(type default)
			)
			(layer "B.Fab")
		)
		(fp_line
			(start -0.12065 -0.3048)
			(end -0.67945 -0.3048)
			(stroke
				(width 0.1)
				(type default)
			)
			(layer "B.Fab")
		)
		(fp_line
			(start -0.12065 -0.2794)
			(end -0.12065 -0.3048)
			(stroke
				(width 0.1)
				(type default)
			)
			(layer "B.Fab")
		)
		(fp_line
			(start -0.120396 0.2794)
			(end 0.12065 0.2794)
			(stroke
				(width 0.1)
				(type default)
			)
			(layer "B.Fab")
		)
		(fp_line
			(start -0.120396 0.3048)
			(end -0.120396 0.2794)
			(stroke
				(width 0.1)
				(type default)
			)
			(layer "B.Fab")
		)
		(fp_line
			(start 0.12065 -0.305054)
			(end 0.12065 -0.2794)
			(stroke
				(width 0.1)
				(type default)
			)
			(layer "B.Fab")
		)
		(fp_line
			(start 0.12065 -0.2794)
			(end -0.12065 -0.2794)
			(stroke
				(width 0.1)
				(type default)
			)
			(layer "B.Fab")
		)
		(fp_line
			(start 0.12065 0.2794)
			(end 0.12065 0.3048)
			(stroke
				(width 0.1)
				(type default)
			)
			(layer "B.Fab")
		)
		(fp_line
			(start 0.12065 0.3048)
			(end 0.67945 0.3048)
			(stroke
				(width 0.1)
				(type default)
			)
			(layer "B.Fab")
		)
		(fp_line
			(start 0.67945 -0.305054)
			(end 0.12065 -0.305054)
			(stroke
				(width 0.1)
				(type default)
			)
			(layer "B.Fab")
		)
		(fp_line
			(start 0.67945 0.3048)
			(end 0.67945 -0.305054)
			(stroke
				(width 0.1)
				(type default)
			)
			(layer "B.Fab")
		)
		(pad "1" smd circle
			(at 0.40005 0 180)
			(size 0 0)
			(layers "B.Cu" "B.Mask" "B.Paste")
			(net "PD_CHF_CPU0_DIMM2_SAA")
		)
		(pad "2" smd circle
			(at -0.40005 0 180)
			(size 0 0)
			(layers "B.Cu" "B.Mask" "B.Paste")
			(net "GND")
		)
	)
	(footprint ""
		(layer "B.Cu")
		(at 110.864396 -357.578406)
		(property "Reference" "PR318"
			(at 0 0 0)
			(layer "B.SilkS")
			(hide yes)
			(effects
				(font
					(size 1.27 1.27)
				)
				(justify mirror)
			)
		)
		(property "Value" ""
			(at 0 0 0)
			(layer "B.Fab")
			(effects
				(font
					(size 1.27 1.27)
				)
				(justify mirror)
			)
		)
		(duplicate_pad_numbers_are_jumpers no)
		(fp_line
			(start -0.7874 -0.4064)
			(end -0.7874 0.4064)
			(stroke
				(width 0.1524)
				(type default)
			)
			(layer "B.SilkS")
		)
		(fp_line
			(start -0.7874 0.4064)
			(end 0.7874 0.4064)
			(stroke
				(width 0.1524)
				(type default)
			)
			(layer "B.SilkS")
		)
		(fp_line
			(start 0.7874 -0.4064)
			(end -0.7874 -0.4064)
			(stroke
				(width 0.1524)
				(type default)
			)
			(layer "B.SilkS")
		)
		(fp_line
			(start 0.7874 0.4064)
			(end 0.7874 -0.4064)
			(stroke
				(width 0.1524)
				(type default)
			)
			(layer "B.SilkS")
		)
		(fp_line
			(start -0.67945 -0.3048)
			(end -0.67945 0.3048)
			(stroke
				(width 0.1)
				(type default)
			)
			(layer "B.Fab")
		)
		(fp_line
			(start -0.67945 0.3048)
			(end -0.120396 0.3048)
			(stroke
				(width 0.1)
				(type default)
			)
			(layer "B.Fab")
		)
		(fp_line
			(start -0.12065 -0.3048)
			(end -0.67945 -0.3048)
			(stroke
				(width 0.1)
				(type default)
			)
			(layer "B.Fab")
		)
		(fp_line
			(start -0.12065 -0.2794)
			(end -0.12065 -0.3048)
			(stroke
				(width 0.1)
				(type default)
			)
			(layer "B.Fab")
		)
		(fp_line
			(start -0.120396 0.2794)
			(end 0.12065 0.2794)
			(stroke
				(width 0.1)
				(type default)
			)
			(layer "B.Fab")
		)
		(fp_line
			(start -0.120396 0.3048)
			(end -0.120396 0.2794)
			(stroke
				(width 0.1)
				(type default)
			)
			(layer "B.Fab")
		)
		(fp_line
			(start 0.12065 -0.305054)
			(end 0.12065 -0.2794)
			(stroke
				(width 0.1)
				(type default)
			)
			(layer "B.Fab")
		)
		(fp_line
			(start 0.12065 -0.2794)
			(end -0.12065 -0.2794)
			(stroke
				(width 0.1)
				(type default)
			)
			(layer "B.Fab")
		)
		(fp_line
			(start 0.12065 0.2794)
			(end 0.12065 0.3048)
			(stroke
				(width 0.1)
				(type default)
			)
			(layer "B.Fab")
		)
		(fp_line
			(start 0.12065 0.3048)
			(end 0.67945 0.3048)
			(stroke
				(width 0.1)
				(type default)
			)
			(layer "B.Fab")
		)
		(fp_line
			(start 0.67945 -0.305054)
			(end 0.12065 -0.305054)
			(stroke
				(width 0.1)
				(type default)
			)
			(layer "B.Fab")
		)
		(fp_line
			(start 0.67945 0.3048)
			(end 0.67945 -0.305054)
			(stroke
				(width 0.1)
				(type default)
			)
			(layer "B.Fab")
		)
		(pad "1" smd circle
			(at 0.40005 0 180)
			(size 0 0)
			(layers "B.Cu" "B.Mask" "B.Paste")
			(net "PVCCIN_CPU1_ADDR")
		)
		(pad "2" smd circle
			(at -0.40005 0 180)
			(size 0 0)
			(layers "B.Cu" "B.Mask" "B.Paste")
			(net "GND")
		)
	)
	(footprint ""
		(layer "B.Cu")
		(at 234.26928 -423.001948 90)
		(property "Reference" "C2294"
			(at 0 0 90)
			(layer "B.SilkS")
			(hide yes)
			(effects
				(font
					(size 1.27 1.27)
				)
				(justify mirror)
			)
		)
		(property "Value" ""
			(at 0 0 90)
			(layer "B.Fab")
			(effects
				(font
					(size 1.27 1.27)
				)
				(justify mirror)
			)
		)
		(duplicate_pad_numbers_are_jumpers no)
		(fp_line
			(start 0.7874 -0.4064)
			(end -0.7874 -0.4064)
			(stroke
				(width 0.1524)
				(type default)
			)
			(layer "B.SilkS")
		)
		(fp_line
			(start -0.7874 -0.4064)
			(end -0.7874 0.4064)
			(stroke
				(width 0.1524)
				(type default)
			)
			(layer "B.SilkS")
		)
		(fp_line
			(start 0.7874 0.4064)
			(end 0.7874 -0.4064)
			(stroke
				(width 0.1524)
				(type default)
			)
			(layer "B.SilkS")
		)
		(fp_line
			(start -0.7874 0.4064)
			(end 0.7874 0.4064)
			(stroke
				(width 0.1524)
				(type default)
			)
			(layer "B.SilkS")
		)
		(fp_line
			(start 0.67945 -0.305054)
			(end 0.12065 -0.305054)
			(stroke
				(width 0.1)
				(type default)
			)
			(layer "B.Fab")
		)
		(fp_line
			(start 0.12065 -0.305054)
			(end 0.12065 -0.2794)
			(stroke
				(width 0.1)
				(type default)
			)
			(layer "B.Fab")
		)
		(fp_line
			(start -0.12065 -0.3048)
			(end -0.67945 -0.3048)
			(stroke
				(width 0.1)
				(type default)
			)
			(layer "B.Fab")
		)
		(fp_line
			(start -0.67945 -0.3048)
			(end -0.67945 0.3048)
			(stroke
				(width 0.1)
				(type default)
			)
			(layer "B.Fab")
		)
		(fp_line
			(start 0.12065 -0.2794)
			(end -0.12065 -0.2794)
			(stroke
				(width 0.1)
				(type default)
			)
			(layer "B.Fab")
		)
		(fp_line
			(start -0.12065 -0.2794)
			(end -0.12065 -0.3048)
			(stroke
				(width 0.1)
				(type default)
			)
			(layer "B.Fab")
		)
		(fp_line
			(start 0.12065 0.2794)
			(end 0.12065 0.3048)
			(stroke
				(width 0.1)
				(type default)
			)
			(layer "B.Fab")
		)
		(fp_line
			(start -0.120396 0.2794)
			(end 0.12065 0.2794)
			(stroke
				(width 0.1)
				(type default)
			)
			(layer "B.Fab")
		)
		(fp_line
			(start 0.67945 0.3048)
			(end 0.67945 -0.305054)
			(stroke
				(width 0.1)
				(type default)
			)
			(layer "B.Fab")
		)
		(fp_line
			(start 0.12065 0.3048)
			(end 0.67945 0.3048)
			(stroke
				(width 0.1)
				(type default)
			)
			(layer "B.Fab")
		)
		(fp_line
			(start -0.120396 0.3048)
			(end -0.120396 0.2794)
			(stroke
				(width 0.1)
				(type default)
			)
			(layer "B.Fab")
		)
		(fp_line
			(start -0.67945 0.3048)
			(end -0.120396 0.3048)
			(stroke
				(width 0.1)
				(type default)
			)
			(layer "B.Fab")
		)
		(pad "1" smd circle
			(at 0.40005 0 270)
			(size 0 0)
			(layers "B.Cu" "B.Mask" "B.Paste")
			(net "PDB_PRSNT_N")
		)
		(pad "2" smd circle
			(at -0.40005 0 270)
			(size 0 0)
			(layers "B.Cu" "B.Mask" "B.Paste")
			(net "GND")
		)
	)
	(footprint ""
		(layer "B.Cu")
		(at 455.093324 -13.09116 90)
		(property "Reference" "R1930"
			(at 0 0 90)
			(layer "B.SilkS")
			(hide yes)
			(effects
				(font
					(size 1.27 1.27)
				)
				(justify mirror)
			)
		)
		(property "Value" ""
			(at 0 0 90)
			(layer "B.Fab")
			(effects
				(font
					(size 1.27 1.27)
				)
				(justify mirror)
			)
		)
		(duplicate_pad_numbers_are_jumpers no)
		(fp_line
			(start 0.7874 -0.4064)
			(end -0.7874 -0.4064)
			(stroke
				(width 0.1524)
				(type default)
			)
			(layer "B.SilkS")
		)
		(fp_line
			(start -0.7874 -0.4064)
			(end -0.7874 0.4064)
			(stroke
				(width 0.1524)
				(type default)
			)
			(layer "B.SilkS")
		)
		(fp_line
			(start 0.7874 0.4064)
			(end 0.7874 -0.4064)
			(stroke
				(width 0.1524)
				(type default)
			)
			(layer "B.SilkS")
		)
		(fp_line
			(start -0.7874 0.4064)
			(end 0.7874 0.4064)
			(stroke
				(width 0.1524)
				(type default)
			)
			(layer "B.SilkS")
		)
		(fp_line
			(start 0.67945 -0.305054)
			(end 0.12065 -0.305054)
			(stroke
				(width 0.1)
				(type default)
			)
			(layer "B.Fab")
		)
		(fp_line
			(start 0.12065 -0.305054)
			(end 0.12065 -0.2794)
			(stroke
				(width 0.1)
				(type default)
			)
			(layer "B.Fab")
		)
		(fp_line
			(start -0.12065 -0.3048)
			(end -0.67945 -0.3048)
			(stroke
				(width 0.1)
				(type default)
			)
			(layer "B.Fab")
		)
		(fp_line
			(start -0.67945 -0.3048)
			(end -0.67945 0.3048)
			(stroke
				(width 0.1)
				(type default)
			)
			(layer "B.Fab")
		)
		(fp_line
			(start 0.12065 -0.2794)
			(end -0.12065 -0.2794)
			(stroke
				(width 0.1)
				(type default)
			)
			(layer "B.Fab")
		)
		(fp_line
			(start -0.12065 -0.2794)
			(end -0.12065 -0.3048)
			(stroke
				(width 0.1)
				(type default)
			)
			(layer "B.Fab")
		)
		(fp_line
			(start 0.12065 0.2794)
			(end 0.12065 0.3048)
			(stroke
				(width 0.1)
				(type default)
			)
			(layer "B.Fab")
		)
		(fp_line
			(start -0.120396 0.2794)
			(end 0.12065 0.2794)
			(stroke
				(width 0.1)
				(type default)
			)
			(layer "B.Fab")
		)
		(fp_line
			(start 0.67945 0.3048)
			(end 0.67945 -0.305054)
			(stroke
				(width 0.1)
				(type default)
			)
			(layer "B.Fab")
		)
		(fp_line
			(start 0.12065 0.3048)
			(end 0.67945 0.3048)
			(stroke
				(width 0.1)
				(type default)
			)
			(layer "B.Fab")
		)
		(fp_line
			(start -0.120396 0.3048)
			(end -0.120396 0.2794)
			(stroke
				(width 0.1)
				(type default)
			)
			(layer "B.Fab")
		)
		(fp_line
			(start -0.67945 0.3048)
			(end -0.120396 0.3048)
			(stroke
				(width 0.1)
				(type default)
			)
			(layer "B.Fab")
		)
		(pad "1" smd circle
			(at 0.40005 0 270)
			(size 0 0)
			(layers "B.Cu" "B.Mask" "B.Paste")
			(net "GND")
		)
		(pad "2" smd circle
			(at -0.40005 0 270)
			(size 0 0)
			(layers "B.Cu" "B.Mask" "B.Paste")
			(net "OCP_SFF_MAIN_PWR_EN")
		)
	)
	(footprint ""
		(layer "B.Cu")
		(at 173.33976 -29.81198 90)
		(property "Reference" "R4770"
			(at 0 0 90)
			(layer "B.SilkS")
			(hide yes)
			(effects
				(font
					(size 1.27 1.27)
				)
				(justify mirror)
			)
		)
		(property "Value" ""
			(at 0 0 90)
			(layer "B.Fab")
			(effects
				(font
					(size 1.27 1.27)
				)
				(justify mirror)
			)
		)
		(duplicate_pad_numbers_are_jumpers no)
		(fp_line
			(start 0.7874 -0.4064)
			(end -0.7874 -0.4064)
			(stroke
				(width 0.1524)
				(type default)
			)
			(layer "B.SilkS")
		)
		(fp_line
			(start -0.7874 -0.4064)
			(end -0.7874 0.4064)
			(stroke
				(width 0.1524)
				(type default)
			)
			(layer "B.SilkS")
		)
		(fp_line
			(start 0.7874 0.4064)
			(end 0.7874 -0.4064)
			(stroke
				(width 0.1524)
				(type default)
			)
			(layer "B.SilkS")
		)
		(fp_line
			(start -0.7874 0.4064)
			(end 0.7874 0.4064)
			(stroke
				(width 0.1524)
				(type default)
			)
			(layer "B.SilkS")
		)
		(fp_line
			(start 0.67945 -0.305054)
			(end 0.12065 -0.305054)
			(stroke
				(width 0.1)
				(type default)
			)
			(layer "B.Fab")
		)
		(fp_line
			(start 0.12065 -0.305054)
			(end 0.12065 -0.2794)
			(stroke
				(width 0.1)
				(type default)
			)
			(layer "B.Fab")
		)
		(fp_line
			(start -0.12065 -0.3048)
			(end -0.67945 -0.3048)
			(stroke
				(width 0.1)
				(type default)
			)
			(layer "B.Fab")
		)
		(fp_line
			(start -0.67945 -0.3048)
			(end -0.67945 0.3048)
			(stroke
				(width 0.1)
				(type default)
			)
			(layer "B.Fab")
		)
		(fp_line
			(start 0.12065 -0.2794)
			(end -0.12065 -0.2794)
			(stroke
				(width 0.1)
				(type default)
			)
			(layer "B.Fab")
		)
		(fp_line
			(start -0.12065 -0.2794)
			(end -0.12065 -0.3048)
			(stroke
				(width 0.1)
				(type default)
			)
			(layer "B.Fab")
		)
		(fp_line
			(start 0.12065 0.2794)
			(end 0.12065 0.3048)
			(stroke
				(width 0.1)
				(type default)
			)
			(layer "B.Fab")
		)
		(fp_line
			(start -0.120396 0.2794)
			(end 0.12065 0.2794)
			(stroke
				(width 0.1)
				(type default)
			)
			(layer "B.Fab")
		)
		(fp_line
			(start 0.67945 0.3048)
			(end 0.67945 -0.305054)
			(stroke
				(width 0.1)
				(type default)
			)
			(layer "B.Fab")
		)
		(fp_line
			(start 0.12065 0.3048)
			(end 0.67945 0.3048)
			(stroke
				(width 0.1)
				(type default)
			)
			(layer "B.Fab")
		)
		(fp_line
			(start -0.120396 0.3048)
			(end -0.120396 0.2794)
			(stroke
				(width 0.1)
				(type default)
			)
			(layer "B.Fab")
		)
		(fp_line
			(start -0.67945 0.3048)
			(end -0.120396 0.3048)
			(stroke
				(width 0.1)
				(type default)
			)
			(layer "B.Fab")
		)
		(pad "1" smd circle
			(at 0.40005 0 270)
			(size 0 0)
			(layers "B.Cu" "B.Mask" "B.Paste")
			(net "HP_LVC3_SCM_HSC_PWRGD_R")
		)
		(pad "2" smd circle
			(at -0.40005 0 270)
			(size 0 0)
			(layers "B.Cu" "B.Mask" "B.Paste")
			(net "HP_LVC3_SCM_HSC_PWRGD")
		)
	)
	(footprint ""
		(layer "B.Cu")
		(at 178.368706 -344.941906 -90)
		(property "Reference" "PC1208_P1_3"
			(at 0 0 90)
			(layer "B.SilkS")
			(hide yes)
			(effects
				(font
					(size 1.27 1.27)
				)
				(justify mirror)
			)
		)
		(property "Value" ""
			(at 0 0 90)
			(layer "B.Fab")
			(effects
				(font
					(size 1.27 1.27)
				)
				(justify mirror)
			)
		)
		(duplicate_pad_numbers_are_jumpers no)
		(fp_line
			(start -1.524 0.762)
			(end 1.524 0.762)
			(stroke
				(width 0.1524)
				(type default)
			)
			(layer "B.SilkS")
		)
		(fp_line
			(start 1.524 0.762)
			(end 1.524 -0.762)
			(stroke
				(width 0.1524)
				(type default)
			)
			(layer "B.SilkS")
		)
		(fp_line
			(start -1.524 -0.762)
			(end -1.524 0.762)
			(stroke
				(width 0.1524)
				(type default)
			)
			(layer "B.SilkS")
		)
		(fp_line
			(start 1.524 -0.762)
			(end -1.524 -0.762)
			(stroke
				(width 0.1524)
				(type default)
			)
			(layer "B.SilkS")
		)
		(fp_line
			(start -1.1049 0.724916)
			(end -1.1049 -0.724916)
			(stroke
				(width 0.1)
				(type default)
			)
			(layer "B.Fab")
		)
		(fp_line
			(start 1.1049 0.724916)
			(end -1.1049 0.724916)
			(stroke
				(width 0.1)
				(type default)
			)
			(layer "B.Fab")
		)
		(fp_line
			(start -1.1049 -0.724916)
			(end 1.1049 -0.724916)
			(stroke
				(width 0.1)
				(type default)
			)
			(layer "B.Fab")
		)
		(fp_line
			(start 1.1049 -0.724916)
			(end 1.1049 0.724916)
			(stroke
				(width 0.1)
				(type default)
			)
			(layer "B.Fab")
		)
		(pad "1" smd rect
			(at 0.889 0 270)
			(size 1.016 1.27)
			(layers "B.Cu" "B.Mask" "B.Paste")
			(net "PVCCFA_EHV_FIVRA_CPU1")
		)
		(pad "2" smd rect
			(at -0.889 0 270)
			(size 1.016 1.27)
			(layers "B.Cu" "B.Mask" "B.Paste")
			(net "GND")
		)
	)
)
